# S9S_MB_2U (Grand Teton) — schematic netlist excerpt (pin names and nets, part order shuffled) for the footprints in the layout excerpt that follows; sources: Cadence DE-HDL packaged netlist, KiCad conversion of 03242023_DA0F0TMBIJ0_F0T_Motherboard_J_brd_V01_OCP.brd

R3667  Q_RES  1K 1% EMPTY  pkg 0402LF  page 250 : A = P3V3_AUX ; B = ADC128_A1
PR569  Q_RES  100 1% CHIP  pkg 0402LF  page 292 : A = VSENSE_PVCCFA_EHV_CPU1_DP ; B = PVCCFA_EHV_CPU1

(kicad_pcb
	(version 20260206)
	(generator "pcbnew")
	(generator_version "10.0")
	(general
		(thickness 1.6)
		(legacy_teardrops no)
	)
	(paper "A4")
	(title_block
		(title "03242023_DA0F0TMBIJ0_F0T_Motherboard_J_brd_V01_OCP.brd")
		(comment 1 "Grand Teton / footprints 3754-3755 of 6105")
	)
	(layers
		(0 "F.Cu" signal "TOP")
		(4 "In1.Cu" signal "GND")
		(6 "In2.Cu" signal "IN1")
		(8 "In3.Cu" signal "GND1")
		(10 "In4.Cu" signal "IN2")
		(12 "In5.Cu" signal "GND2")
		(14 "In6.Cu" signal "IN3")
		(16 "In7.Cu" signal "GND3")
		(18 "In8.Cu" signal "VCC")
		(20 "In9.Cu" signal "VCC1")
		(22 "In10.Cu" signal "GND4")
		(24 "In11.Cu" signal "IN4")
		(26 "In12.Cu" signal "GND5")
		(28 "In13.Cu" signal "IN5")
		(30 "In14.Cu" signal "GND6")
		(32 "In15.Cu" signal "IN6")
		(34 "In16.Cu" signal "GND7")
		(2 "B.Cu" signal "BOTTOM")
		(9 "F.Adhes" user "F.Adhesive")
		(11 "B.Adhes" user "B.Adhesive")
		(13 "F.Paste" user "Package Geometry/Pastemask Top")
		(15 "B.Paste" user "Package Geometry/Pastemask Bottom")
		(5 "F.SilkS" user "Ref Des/Silkscreen Top")
		(7 "B.SilkS" user "Ref Des/Silkscreen Bottom")
		(1 "F.Mask" user "Board Geometry/Soldermask Top")
		(3 "B.Mask" user "Board Geometry/Soldermask Bottom")
		(17 "Dwgs.User" user "User.Drawings")
		(19 "Cmts.User" user "User.Comments")
		(21 "Eco1.User" user "User.Eco1")
		(23 "Eco2.User" user "User.Eco2")
		(25 "Edge.Cuts" user "Board Geometry/Outline")
		(27 "Margin" user)
		(31 "F.CrtYd" user "Package Geometry/Place Bound Top")
		(29 "B.CrtYd" user "Package Geometry/Place Bound Bottom")
		(35 "F.Fab" user "Ref Des/Assembly Top")
		(33 "B.Fab" user "Ref Des/Assembly Bottom")
	)
	(footprint ""
		(layer "F.Cu")
		(at 73.506076 -174.008034 180)
		(property "Reference" "PR569"
			(at 0 0 180)
			(layer "F.SilkS")
			(hide yes)
			(effects
				(font
					(size 1.27 1.27)
				)
			)
		)
		(property "Value" ""
			(at 0 0 180)
			(layer "F.Fab")
			(effects
				(font
					(size 1.27 1.27)
				)
			)
		)
		(duplicate_pad_numbers_are_jumpers no)
		(fp_line
			(start 0.7874 0.4064)
			(end -0.7874 0.4064)
			(stroke
				(width 0.1524)
				(type default)
			)
			(layer "F.SilkS")
		)
		(fp_line
			(start 0.7874 -0.4064)
			(end 0.7874 0.4064)
			(stroke
				(width 0.1524)
				(type default)
			)
			(layer "F.SilkS")
		)
		(fp_line
			(start -0.7874 0.4064)
			(end -0.7874 -0.4064)
			(stroke
				(width 0.1524)
				(type default)
			)
			(layer "F.SilkS")
		)
		(fp_line
			(start -0.7874 -0.4064)
			(end 0.7874 -0.4064)
			(stroke
				(width 0.1524)
				(type default)
			)
			(layer "F.SilkS")
		)
		(fp_line
			(start 0.67945 0.3048)
			(end 0.120396 0.3048)
			(stroke
				(width 0.1)
				(type default)
			)
			(layer "F.Fab")
		)
		(fp_line
			(start 0.67945 -0.3048)
			(end 0.67945 0.3048)
			(stroke
				(width 0.1)
				(type default)
			)
			(layer "F.Fab")
		)
		(fp_line
			(start 0.12065 -0.2794)
			(end 0.12065 -0.3048)
			(stroke
				(width 0.1)
				(type default)
			)
			(layer "F.Fab")
		)
		(fp_line
			(start 0.12065 -0.3048)
			(end 0.67945 -0.3048)
			(stroke
				(width 0.1)
				(type default)
			)
			(layer "F.Fab")
		)
		(fp_line
			(start 0.120396 0.3048)
			(end 0.120396 0.2794)
			(stroke
				(width 0.1)
				(type default)
			)
			(layer "F.Fab")
		)
		(fp_line
			(start 0.120396 0.2794)
			(end -0.12065 0.2794)
			(stroke
				(width 0.1)
				(type default)
			)
			(layer "F.Fab")
		)
		(fp_line
			(start -0.12065 0.3048)
			(end -0.67945 0.3048)
			(stroke
				(width 0.1)
				(type default)
			)
			(layer "F.Fab")
		)
		(fp_line
			(start -0.12065 0.2794)
			(end -0.12065 0.3048)
			(stroke
				(width 0.1)
				(type default)
			)
			(layer "F.Fab")
		)
		(fp_line
			(start -0.12065 -0.2794)
			(end 0.12065 -0.2794)
			(stroke
				(width 0.1)
				(type default)
			)
			(layer "F.Fab")
		)
		(fp_line
			(start -0.12065 -0.305054)
			(end -0.12065 -0.2794)
			(stroke
				(width 0.1)
				(type default)
			)
			(layer "F.Fab")
		)
		(fp_line
			(start -0.67945 0.3048)
			(end -0.67945 -0.305054)
			(stroke
				(width 0.1)
				(type default)
			)
			(layer "F.Fab")
		)
		(fp_line
			(start -0.67945 -0.305054)
			(end -0.12065 -0.305054)
			(stroke
				(width 0.1)
				(type default)
			)
			(layer "F.Fab")
		)
		(pad "1" smd circle
			(at -0.40005 0 180)
			(size 0 0)
			(layers "F.Cu" "F.Mask" "F.Paste")
			(net "VSENSE_PVCCFA_EHV_CPU1_DP")
		)
		(pad "2" smd circle
			(at 0.40005 0 180)
			(size 0 0)
			(layers "F.Cu" "F.Mask" "F.Paste")
			(net "PVCCFA_EHV_CPU1")
		)
	)
	(footprint ""
		(layer "F.Cu")
		(at 20.190714 -106.761026)
		(property "Reference" "R3667"
			(at 0 0 0)
			(layer "F.SilkS")
			(hide yes)
			(effects
				(font
					(size 1.27 1.27)
				)
			)
		)
		(property "Value" ""
			(at 0 0 0)
			(layer "F.Fab")
			(effects
				(font
					(size 1.27 1.27)
				)
			)
		)
		(duplicate_pad_numbers_are_jumpers no)
		(fp_line
			(start -0.7874 -0.4064)
			(end 0.7874 -0.4064)
			(stroke
				(width 0.1524)
				(type default)
			)
			(layer "F.SilkS")
		)
		(fp_line
			(start -0.7874 0.4064)
			(end -0.7874 -0.4064)
			(stroke
				(width 0.1524)
				(type default)
			)
			(layer "F.SilkS")
		)
		(fp_line
			(start 0.7874 -0.4064)
			(end 0.7874 0.4064)
			(stroke
				(width 0.1524)
				(type default)
			)
			(layer "F.SilkS")
		)
		(fp_line
			(start 0.7874 0.4064)
			(end -0.7874 0.4064)
			(stroke
				(width 0.1524)
				(type default)
			)
			(layer "F.SilkS")
		)
		(fp_line
			(start -0.67945 -0.305054)
			(end -0.12065 -0.305054)
			(stroke
				(width 0.1)
				(type default)
			)
			(layer "F.Fab")
		)
		(fp_line
			(start -0.67945 0.3048)
			(end -0.67945 -0.305054)
			(stroke
				(width 0.1)
				(type default)
			)
			(layer "F.Fab")
		)
		(fp_line
			(start -0.12065 -0.305054)
			(end -0.12065 -0.2794)
			(stroke
				(width 0.1)
				(type default)
			)
			(layer "F.Fab")
		)
		(fp_line
			(start -0.12065 -0.2794)
			(end 0.12065 -0.2794)
			(stroke
				(width 0.1)
				(type default)
			)
			(layer "F.Fab")
		)
		(fp_line
			(start -0.12065 0.2794)
			(end -0.12065 0.3048)
			(stroke
				(width 0.1)
				(type default)
			)
			(layer "F.Fab")
		)
		(fp_line
			(start -0.12065 0.3048)
			(end -0.67945 0.3048)
			(stroke
				(width 0.1)
				(type default)
			)
			(layer "F.Fab")
		)
		(fp_line
			(start 0.120396 0.2794)
			(end -0.12065 0.2794)
			(stroke
				(width 0.1)
				(type default)
			)
			(layer "F.Fab")
		)
		(fp_line
			(start 0.120396 0.3048)
			(end 0.120396 0.2794)
			(stroke
				(width 0.1)
				(type default)
			)
			(layer "F.Fab")
		)
		(fp_line
			(start 0.12065 -0.3048)
			(end 0.67945 -0.3048)
			(stroke
				(width 0.1)
				(type default)
			)
			(layer "F.Fab")
		)
		(fp_line
			(start 0.12065 -0.2794)
			(end 0.12065 -0.3048)
			(stroke
				(width 0.1)
				(type default)
			)
			(layer "F.Fab")
		)
		(fp_line
			(start 0.67945 -0.3048)
			(end 0.67945 0.3048)
			(stroke
				(width 0.1)
				(type default)
			)
			(layer "F.Fab")
		)
		(fp_line
			(start 0.67945 0.3048)
			(end 0.120396 0.3048)
			(stroke
				(width 0.1)
				(type default)
			)
			(layer "F.Fab")
		)
		(pad "1" smd circle
			(at -0.40005 0)
			(size 0 0)
			(layers "F.Cu" "F.Mask" "F.Paste")
			(net "P3V3_AUX")
		)
		(pad "2" smd circle
			(at 0.40005 0)
			(size 0 0)
			(layers "F.Cu" "F.Mask" "F.Paste")
			(net "ADC128_A1")
		)
	)
)
